# S9S_MB_2U (Grand Teton) — schematic netlist excerpt (pin names and nets, part order shuffled) for the footprints in the layout excerpt that follows; sources: Cadence DE-HDL packaged netlist, KiCad conversion of 03242023_DA0F0TMBIJ0_F0T_Motherboard_J_brd_V01_OCP.brd

R4403  Q_RES  1.5K 1% CHIP  pkg 0402LF  page 122 : A = H_CPU0_MEMHOT_OUT ; B = H_CPU0_MEMHOT_OUT_R
R3662  Q_RES  0 5% CHIP  pkg 0402LF  page 152 : A = P3V3_AUX_USB_HUB ; B = USB_HUB_DVDD

(kicad_pcb
	(version 20260206)
	(generator "pcbnew")
	(generator_version "10.0")
	(general
		(thickness 1.6)
		(legacy_teardrops no)
	)
	(paper "A4")
	(title_block
		(title "03242023_DA0F0TMBIJ0_F0T_Motherboard_J_brd_V01_OCP.brd")
		(comment 1 "Grand Teton / footprints 1480-1481 of 6105")
	)
	(layers
		(0 "F.Cu" signal "TOP")
		(4 "In1.Cu" signal "GND")
		(6 "In2.Cu" signal "IN1")
		(8 "In3.Cu" signal "GND1")
		(10 "In4.Cu" signal "IN2")
		(12 "In5.Cu" signal "GND2")
		(14 "In6.Cu" signal "IN3")
		(16 "In7.Cu" signal "GND3")
		(18 "In8.Cu" signal "VCC")
		(20 "In9.Cu" signal "VCC1")
		(22 "In10.Cu" signal "GND4")
		(24 "In11.Cu" signal "IN4")
		(26 "In12.Cu" signal "GND5")
		(28 "In13.Cu" signal "IN5")
		(30 "In14.Cu" signal "GND6")
		(32 "In15.Cu" signal "IN6")
		(34 "In16.Cu" signal "GND7")
		(2 "B.Cu" signal "BOTTOM")
		(9 "F.Adhes" user "F.Adhesive")
		(11 "B.Adhes" user "B.Adhesive")
		(13 "F.Paste" user "Package Geometry/Pastemask Top")
		(15 "B.Paste" user "Package Geometry/Pastemask Bottom")
		(5 "F.SilkS" user "Ref Des/Silkscreen Top")
		(7 "B.SilkS" user "Ref Des/Silkscreen Bottom")
		(1 "F.Mask" user "Board Geometry/Soldermask Top")
		(3 "B.Mask" user "Board Geometry/Soldermask Bottom")
		(17 "Dwgs.User" user "User.Drawings")
		(19 "Cmts.User" user "User.Comments")
		(21 "Eco1.User" user "User.Eco1")
		(23 "Eco2.User" user "User.Eco2")
		(25 "Edge.Cuts" user "Board Geometry/Outline")
		(27 "Margin" user)
		(31 "F.CrtYd" user "Package Geometry/Place Bound Top")
		(29 "B.CrtYd" user "Package Geometry/Place Bound Bottom")
		(35 "F.Fab" user "Ref Des/Assembly Top")
		(33 "B.Fab" user "Ref Des/Assembly Bottom")
	)
	(footprint ""
		(layer "F.Cu")
		(at 17.190974 -92.687648 90)
		(property "Reference" "R3662"
			(at 0 0 90)
			(layer "F.SilkS")
			(hide yes)
			(effects
				(font
					(size 1.27 1.27)
				)
			)
		)
		(property "Value" ""
			(at 0 0 90)
			(layer "F.Fab")
			(effects
				(font
					(size 1.27 1.27)
				)
			)
		)
		(duplicate_pad_numbers_are_jumpers no)
		(fp_line
			(start 0.7874 -0.4064)
			(end 0.7874 0.4064)
			(stroke
				(width 0.1524)
				(type default)
			)
			(layer "F.SilkS")
		)
		(fp_line
			(start -0.7874 -0.4064)
			(end 0.7874 -0.4064)
			(stroke
				(width 0.1524)
				(type default)
			)
			(layer "F.SilkS")
		)
		(fp_line
			(start 0.7874 0.4064)
			(end -0.7874 0.4064)
			(stroke
				(width 0.1524)
				(type default)
			)
			(layer "F.SilkS")
		)
		(fp_line
			(start -0.7874 0.4064)
			(end -0.7874 -0.4064)
			(stroke
				(width 0.1524)
				(type default)
			)
			(layer "F.SilkS")
		)
		(fp_line
			(start -0.12065 -0.305054)
			(end -0.12065 -0.2794)
			(stroke
				(width 0.1)
				(type default)
			)
			(layer "F.Fab")
		)
		(fp_line
			(start -0.67945 -0.305054)
			(end -0.12065 -0.305054)
			(stroke
				(width 0.1)
				(type default)
			)
			(layer "F.Fab")
		)
		(fp_line
			(start 0.67945 -0.3048)
			(end 0.67945 0.3048)
			(stroke
				(width 0.1)
				(type default)
			)
			(layer "F.Fab")
		)
		(fp_line
			(start 0.12065 -0.3048)
			(end 0.67945 -0.3048)
			(stroke
				(width 0.1)
				(type default)
			)
			(layer "F.Fab")
		)
		(fp_line
			(start 0.12065 -0.2794)
			(end 0.12065 -0.3048)
			(stroke
				(width 0.1)
				(type default)
			)
			(layer "F.Fab")
		)
		(fp_line
			(start -0.12065 -0.2794)
			(end 0.12065 -0.2794)
			(stroke
				(width 0.1)
				(type default)
			)
			(layer "F.Fab")
		)
		(fp_line
			(start 0.120396 0.2794)
			(end -0.12065 0.2794)
			(stroke
				(width 0.1)
				(type default)
			)
			(layer "F.Fab")
		)
		(fp_line
			(start -0.12065 0.2794)
			(end -0.12065 0.3048)
			(stroke
				(width 0.1)
				(type default)
			)
			(layer "F.Fab")
		)
		(fp_line
			(start 0.67945 0.3048)
			(end 0.120396 0.3048)
			(stroke
				(width 0.1)
				(type default)
			)
			(layer "F.Fab")
		)
		(fp_line
			(start 0.120396 0.3048)
			(end 0.120396 0.2794)
			(stroke
				(width 0.1)
				(type default)
			)
			(layer "F.Fab")
		)
		(fp_line
			(start -0.12065 0.3048)
			(end -0.67945 0.3048)
			(stroke
				(width 0.1)
				(type default)
			)
			(layer "F.Fab")
		)
		(fp_line
			(start -0.67945 0.3048)
			(end -0.67945 -0.305054)
			(stroke
				(width 0.1)
				(type default)
			)
			(layer "F.Fab")
		)
		(pad "1" smd circle
			(at -0.40005 0 90)
			(size 0 0)
			(layers "F.Cu" "F.Mask" "F.Paste")
			(net "P3V3_AUX_USB_HUB")
		)
		(pad "2" smd circle
			(at 0.40005 0 90)
			(size 0 0)
			(layers "F.Cu" "F.Mask" "F.Paste")
			(net "USB_HUB_DVDD")
		)
	)
	(footprint ""
		(layer "F.Cu")
		(at 128.02616 -96.495108 90)
		(property "Reference" "R4403"
			(at 0 0 90)
			(layer "F.SilkS")
			(hide yes)
			(effects
				(font
					(size 1.27 1.27)
				)
			)
		)
		(property "Value" ""
			(at 0 0 90)
			(layer "F.Fab")
			(effects
				(font
					(size 1.27 1.27)
				)
			)
		)
		(duplicate_pad_numbers_are_jumpers no)
		(fp_line
			(start 0.7874 -0.4064)
			(end 0.7874 0.4064)
			(stroke
				(width 0.1524)
				(type default)
			)
			(layer "F.SilkS")
		)
		(fp_line
			(start -0.7874 -0.4064)
			(end 0.7874 -0.4064)
			(stroke
				(width 0.1524)
				(type default)
			)
			(layer "F.SilkS")
		)
		(fp_line
			(start 0.7874 0.4064)
			(end -0.7874 0.4064)
			(stroke
				(width 0.1524)
				(type default)
			)
			(layer "F.SilkS")
		)
		(fp_line
			(start -0.7874 0.4064)
			(end -0.7874 -0.4064)
			(stroke
				(width 0.1524)
				(type default)
			)
			(layer "F.SilkS")
		)
		(fp_line
			(start -0.12065 -0.305054)
			(end -0.12065 -0.2794)
			(stroke
				(width 0.1)
				(type default)
			)
			(layer "F.Fab")
		)
		(fp_line
			(start -0.67945 -0.305054)
			(end -0.12065 -0.305054)
			(stroke
				(width 0.1)
				(type default)
			)
			(layer "F.Fab")
		)
		(fp_line
			(start 0.67945 -0.3048)
			(end 0.67945 0.3048)
			(stroke
				(width 0.1)
				(type default)
			)
			(layer "F.Fab")
		)
		(fp_line
			(start 0.12065 -0.3048)
			(end 0.67945 -0.3048)
			(stroke
				(width 0.1)
				(type default)
			)
			(layer "F.Fab")
		)
		(fp_line
			(start 0.12065 -0.2794)
			(end 0.12065 -0.3048)
			(stroke
				(width 0.1)
				(type default)
			)
			(layer "F.Fab")
		)
		(fp_line
			(start -0.12065 -0.2794)
			(end 0.12065 -0.2794)
			(stroke
				(width 0.1)
				(type default)
			)
			(layer "F.Fab")
		)
		(fp_line
			(start 0.120396 0.2794)
			(end -0.12065 0.2794)
			(stroke
				(width 0.1)
				(type default)
			)
			(layer "F.Fab")
		)
		(fp_line
			(start -0.12065 0.2794)
			(end -0.12065 0.3048)
			(stroke
				(width 0.1)
				(type default)
			)
			(layer "F.Fab")
		)
		(fp_line
			(start 0.67945 0.3048)
			(end 0.120396 0.3048)
			(stroke
				(width 0.1)
				(type default)
			)
			(layer "F.Fab")
		)
		(fp_line
			(start 0.120396 0.3048)
			(end 0.120396 0.2794)
			(stroke
				(width 0.1)
				(type default)
			)
			(layer "F.Fab")
		)
		(fp_line
			(start -0.12065 0.3048)
			(end -0.67945 0.3048)
			(stroke
				(width 0.1)
				(type default)
			)
			(layer "F.Fab")
		)
		(fp_line
			(start -0.67945 0.3048)
			(end -0.67945 -0.305054)
			(stroke
				(width 0.1)
				(type default)
			)
			(layer "F.Fab")
		)
		(pad "1" smd circle
			(at -0.40005 0 90)
			(size 0 0)
			(layers "F.Cu" "F.Mask" "F.Paste")
			(net "H_CPU0_MEMHOT_OUT")
		)
		(pad "2" smd circle
			(at 0.40005 0 90)
			(size 0 0)
			(layers "F.Cu" "F.Mask" "F.Paste")
			(net "H_CPU0_MEMHOT_OUT_R")
		)
	)
)
